# BASEBOARD_FAB2 (Tioga Pass) — schematic netlist excerpt (pin names and nets, part order shuffled) for the footprints in the layout excerpt that follows; sources: Cadence DE-HDL packaged netlist, KiCad conversion of Wiwynn_Tioga_Pass_MB.brd

EU4D1  IR354XX  IR35411 IC  pkg SM  page 203
  VOS  = PVCCIN_CPU0
  LGND  = GND
  VCC  = VR_PVCCIN_CPU0_PH4_VCIN
  VDRV  = P5V_STBY
  PGND(0)  = GND
  GL(0)  = TP_PVCCIN_CPU0_PH4_GL_0
  PGND(1)  = GND
  SW  = VR_PVCCIN_CPU0_PHASE4
  VIN(0)  = VR_FET_SW_P12V_STBY_PVCCIN_CPU0
  VIN(1)  = VR_FET_SW_P12V_STBY_PVCCIN_CPU0
  NC  = NC
  PHASE  = VR_PVCCIN_CPU0_PH4_PHASE
  BOOST  = VR_PVCCIN_CPU0_PH4_BOOT_R
  PWM  = VR_PVCCIN_CPU0_PWM4
  EN  = P5V_STBY
  TOUT_FLT  = A_TSENSE_PVCCIN_CPU0
  OCSET  = VR_PVCCIN_CPU0_PH4_OCSET
  IOUT  = ISENSE_PVCCIN_CPU0_PH4_IMON
  REFIN  = VR_PVCCIN_CPU0_AIREF4
  PGND(2)  = GND
  GL(1)  = TP_PVCCIN_CPU0_PH4_GL_1

(kicad_pcb
	(version 20260206)
	(generator "pcbnew")
	(generator_version "10.0")
	(general
		(thickness 1.6)
		(legacy_teardrops no)
	)
	(paper "A4")
	(title_block
		(title "Wiwynn_Tioga_Pass_MB.brd")
		(comment 1 "Tioga Pass / footprints 184-184 of 4770")
	)
	(layers
		(0 "F.Cu" signal "TOP")
		(4 "In1.Cu" signal "L2GND")
		(6 "In2.Cu" signal "L3")
		(8 "In3.Cu" signal "L4GND")
		(10 "In4.Cu" signal "L5")
		(12 "In5.Cu" signal "L6GND")
		(14 "In6.Cu" signal "L7VCC")
		(16 "In7.Cu" signal "L8VCC")
		(18 "In8.Cu" signal "L9GND")
		(20 "In9.Cu" signal "L10")
		(22 "In10.Cu" signal "L11GND")
		(24 "In11.Cu" signal "L12")
		(26 "In12.Cu" signal "L13GND")
		(2 "B.Cu" signal "BOTTOM")
		(9 "F.Adhes" user "F.Adhesive")
		(11 "B.Adhes" user "B.Adhesive")
		(13 "F.Paste" user "Package Geometry/Pastemask Top")
		(15 "B.Paste" user "Package Geometry/Pastemask Bottom")
		(5 "F.SilkS" user "Ref Des/Silkscreen Top")
		(7 "B.SilkS" user "Ref Des/Silkscreen Bottom")
		(1 "F.Mask" user "Board Geometry/Soldermask Top")
		(3 "B.Mask" user "Board Geometry/Soldermask Bottom")
		(17 "Dwgs.User" user "User.Drawings")
		(19 "Cmts.User" user "User.Comments")
		(21 "Eco1.User" user "User.Eco1")
		(23 "Eco2.User" user "User.Eco2")
		(25 "Edge.Cuts" user "Board Geometry/Outline")
		(27 "Margin" user)
		(31 "F.CrtYd" user "Package Geometry/Place Bound Top")
		(29 "B.CrtYd" user "Package Geometry/Place Bound Bottom")
		(35 "F.Fab" user "Ref Des/Assembly Top")
		(33 "B.Fab" user "Ref Des/Assembly Bottom")
	)
	(footprint ""
		(layer "F.Cu")
		(at 198.925434 -81.423764 90)
		(property "Reference" "EU4D1"
			(at 3.334766 -1.542034 0)
			(unlocked yes)
			(layer "F.SilkS")
			(effects
				(font
					(size 0.7874 0.5842)
					(thickness 0.1524)
				)
			)
		)
		(property "Value" ""
			(at 0 0 90)
			(layer "F.Fab")
			(effects
				(font
					(size 1.27 1.27)
				)
			)
		)
		(duplicate_pad_numbers_are_jumpers no)
		(fp_line
			(start 2.9718 -3.5052)
			(end 2.9718 3.429)
			(stroke
				(width 0.1524)
				(type default)
			)
			(layer "F.SilkS")
		)
		(fp_line
			(start -3.0099 -3.5052)
			(end 2.9718 -3.5052)
			(stroke
				(width 0.1524)
				(type default)
			)
			(layer "F.SilkS")
		)
		(fp_line
			(start 2.9718 3.429)
			(end -3.0099 3.429)
			(stroke
				(width 0.1524)
				(type default)
			)
			(layer "F.SilkS")
		)
		(fp_line
			(start -3.0099 3.429)
			(end -3.0099 -3.5052)
			(stroke
				(width 0.1524)
				(type default)
			)
			(layer "F.SilkS")
		)
		(fp_circle
			(center -3.057398 -2.678684)
			(end -3.057398 -2.551684)
			(stroke
				(width 0.254)
				(type default)
			)
			(fill no)
			(layer "F.SilkS")
		)
		(fp_poly
			(pts
				(xy -2.9972 -3.4925) (xy -2.9972 -2.6924) (xy -2.1971 -3.4925)
			)
			(stroke
				(width 0)
				(type default)
			)
			(fill yes)
			(layer "F.SilkS")
		)
		(fp_poly
			(pts
				(xy -2.549906 -3.050032) (xy -2.549906 3.050032) (xy 2.549906 3.050032) (xy 2.549906 -3.050032)
			)
			(stroke
				(width 0)
				(type default)
			)
			(fill no)
			(layer "F.CrtYd")
		)
		(fp_line
			(start 2.549906 -3.050032)
			(end 2.549906 3.050032)
			(stroke
				(width 0.1)
				(type default)
			)
			(layer "F.Fab")
		)
		(fp_line
			(start -2.549906 -3.050032)
			(end 2.549906 -3.050032)
			(stroke
				(width 0.1)
				(type default)
			)
			(layer "F.Fab")
		)
		(fp_line
			(start 2.549906 3.050032)
			(end -2.549906 3.050032)
			(stroke
				(width 0.1)
				(type default)
			)
			(layer "F.Fab")
		)
		(fp_line
			(start -2.549906 3.050032)
			(end -2.549906 -3.050032)
			(stroke
				(width 0.1)
				(type default)
			)
			(layer "F.Fab")
		)
		(fp_circle
			(center -3.057398 -2.678684)
			(end -3.057398 -2.551684)
			(stroke
				(width 0.254)
				(type default)
			)
			(fill no)
			(layer "F.Fab")
		)
		(pad "1" smd rect
			(at -2.39522 -2.279904 90)
			(size 0.7112 0.254)
			(layers "F.Cu" "F.Mask" "F.Paste")
			(net "PVCCIN_CPU0")
		)
		(pad "2" smd rect
			(at -2.39522 -1.83007 90)
			(size 0.7112 0.254)
			(layers "F.Cu" "F.Mask" "F.Paste")
			(net "GND")
		)
		(pad "3" smd rect
			(at -2.39522 -1.379982 90)
			(size 0.7112 0.254)
			(layers "F.Cu" "F.Mask" "F.Paste")
			(net "VR_PVCCIN_CPU0_PH4_VCIN")
		)
		(pad "4" smd rect
			(at -2.39522 -0.929894 90)
			(size 0.7112 0.254)
			(layers "F.Cu" "F.Mask" "F.Paste")
			(net "P5V_STBY")
		)
		(pad "5" smd rect
			(at -2.39522 -0.48006 90)
			(size 0.7112 0.254)
			(layers "F.Cu" "F.Mask" "F.Paste")
			(net "GND")
		)
		(pad "6" smd rect
			(at -2.39522 -0.029972 90)
			(size 0.7112 0.254)
			(layers "F.Cu" "F.Mask" "F.Paste")
			(net "TP_PVCCIN_CPU0_PH4_GL_0")
		)
		(pad "7" smd custom
			(at 0.016764 1.145032 90)
			(size 0.53975 0.53975)
			(layers "F.Cu" "F.Mask" "F.Paste")
			(net "GND")
			(options
				(clearance outline)
				(anchor circle)
			)
			(primitives
				(gr_poly
					(pts
						(xy -2.7051 1.0795) (xy -2.7051 -0.3683) (xy -0.9271 -0.3683) (xy -0.9271 -1.0795) (xy 2.7051 -1.0795)
						(xy 2.7051 1.0795)
					)
					(width 0)
					(fill yes)
				)
			)
		)
		(pad "10" smd rect
			(at -0.008382 2.874772 90)
			(size 4.3434 0.6096)
			(layers "F.Cu" "F.Mask" "F.Paste")
			(net "VR_PVCCIN_CPU0_PHASE4")
		)
		(pad "25" smd rect
			(at 1.548384 -1.283208 90)
			(size 2.3368 2.0066)
			(layers "F.Cu" "F.Mask" "F.Paste")
			(net "VR_FET_SW_P12V_STBY_PVCCIN_CPU0")
		)
		(pad "30" smd rect
			(at 2.050034 -2.895092 90)
			(size 0.254 0.7112)
			(layers "F.Cu" "F.Mask" "F.Paste")
			(net "VR_FET_SW_P12V_STBY_PVCCIN_CPU0")
		)
		(pad "31" smd rect
			(at 1.599946 -2.895092 90)
			(size 0.254 0.7112)
			(layers "F.Cu" "F.Mask" "F.Paste")
			(net "Net_364")
		)
		(pad "32" smd rect
			(at 1.150112 -2.895092 90)
			(size 0.254 0.7112)
			(layers "F.Cu" "F.Mask" "F.Paste")
			(net "VR_PVCCIN_CPU0_PH4_PHASE")
		)
		(pad "33" smd rect
			(at 0.700024 -2.895092 90)
			(size 0.254 0.7112)
			(layers "F.Cu" "F.Mask" "F.Paste")
			(net "VR_PVCCIN_CPU0_PH4_BOOT_R")
		)
		(pad "34" smd rect
			(at 0.249936 -2.895092 90)
			(size 0.254 0.7112)
			(layers "F.Cu" "F.Mask" "F.Paste")
			(net "VR_PVCCIN_CPU0_PWM4")
		)
		(pad "35" smd rect
			(at -0.199898 -2.895092 90)
			(size 0.254 0.7112)
			(layers "F.Cu" "F.Mask" "F.Paste")
			(net "P5V_STBY")
		)
		(pad "36" smd rect
			(at -0.649986 -2.895092 90)
			(size 0.254 0.7112)
			(layers "F.Cu" "F.Mask" "F.Paste")
			(net "A_TSENSE_PVCCIN_CPU0")
		)
		(pad "37" smd rect
			(at -1.100074 -2.895092 90)
			(size 0.254 0.7112)
			(layers "F.Cu" "F.Mask" "F.Paste")
			(net "VR_PVCCIN_CPU0_PH4_OCSET")
		)
		(pad "38" smd rect
			(at -1.549908 -2.895092 90)
			(size 0.254 0.7112)
			(layers "F.Cu" "F.Mask" "F.Paste")
			(net "ISENSE_PVCCIN_CPU0_PH4_IMON")
		)
		(pad "39" smd rect
			(at -1.999996 -2.895092 90)
			(size 0.254 0.7112)
			(layers "F.Cu" "F.Mask" "F.Paste")
			(net "VR_PVCCIN_CPU0_AIREF4")
		)
		(pad "40" smd rect
			(at -0.871728 -1.283208 90)
			(size 1.8034 2.0066)
			(layers "F.Cu" "F.Mask" "F.Paste")
			(net "GND")
		)
		(pad "41" smd rect
			(at -1.533906 0.247904 90)
			(size 0.508 0.3556)
			(layers "F.Cu" "F.Mask" "F.Paste")
			(net "TP_PVCCIN_CPU0_PH4_GL_1")
		)
	)
)
